FILE_TYPE = CONNECTIVITY;
{Allegro Design Entry HDL 17.2-2016 S081 (4005846) 1/11/2022}
"PAGE_NUMBER" = 122;
0"NC";
1"PVNN_TERM_CPU1\g";
2"PVNN_TERM_CPU1\g";
3"PVNN_TERM_CPU0\g";
4"PVNN_TERM_CPU0\g";
5"P3V3\g";
6"P3V3\g";
7"PVNN_TERM_CPU1\g";
8"PVNN_TERM_CPU0\g";
9"GND\g";
10"GND\g";
11"H_CPU1_MEMHOT_IN_LVC1_N";
12"H_CPU0_MEMHOT_IN_LVC1_N";
13"H_CPU0_MEMHOT_OUT_LVC1_N";
14"H_CPU1_MEMHOT_IN_LVC1_R1_N";
15"H_CPU0_MEMHOT_OUT_VT_N";
16"H_CPU0_MEMHOT_OUT_R";
17"H_CPU1_MEMHOT_OUT_R";
18"H_CPU1_MEMHOT_OUT_LVC1_N";
19"H_CPU1_MEMHOT_OUT_VT_N";
20"H_CPU0_MEMHOT_IN_LVC1_R1_N";
21"H_CPU0_MEMHOT_OUT";
22"H_CPU1_MEMHOT_OUT";
23"H_CPU0_MEMHOT_OUT_VT_R_N";
24"H_CPU1_MEMHOT_OUT_VT_R_N";
25"H_CPU0_MEMHOT_OUT_LVC1_R_N";
26"H_CPU0_MEMHOT_IN_LVC1_R_N";
27"H_CPU1_MEMHOT_OUT_LVC1_R_N";
28"H_CPU1_MEMHOT_IN_LVC1_R_N";
%"BC847BPN"
"2","(-650,825)","0","pure_quanta","I10";
;
PART_NUMBER"BA008470026"
PART_TYPE"SMLF"
MATERIAL"IC"
VALUE"BC847BPN"
LOCATION"Q142"
CDS_LMAN_SYM_OUTLINE"-50,50,50,-50"
NEEDS_NO_SIZE"TRUE"
CDS_LIB"pure_quanta"
$SEC"2"
CDS_SEC"2";
"E2"
$PN"4"2;
"C2"
$PN"3"22;
"B2"
$PN"5"24;
%"UNIVERSAL_POWER"
"1","(-600,1075)","0","logical_power","I11";
;
HDL_POWER"PVNN_TERM_CPU1"
CDS_LIB"logical_power";
"A"2;
%"BC847BPN"
"2","(-650,2175)","0","pure_quanta","I12";
;
PART_NUMBER"BA008470026"
VALUE"BC847BPN"
MATERIAL"IC"
PART_TYPE"SMLF"
LOCATION"Q143"
CDS_LMAN_SYM_OUTLINE"-50,50,50,-50"
NEEDS_NO_SIZE"TRUE"
CDS_LIB"pure_quanta"
$SEC"2"
CDS_SEC"2";
"E2"
$PN"4"3;
"C2"
$PN"3"21;
"B2"
$PN"5"23;
%"UNIVERSAL_POWER"
"1","(-600,2425)","0","logical_power","I13";
;
HDL_POWER"PVNN_TERM_CPU0"
CDS_LIB"logical_power";
"A"3;
%"UNIVERSAL_POWER"
"1","(-2000,2650)","0","logical_power","I14";
;
HDL_POWER"PVNN_TERM_CPU0"
CDS_LIB"logical_power";
"A"4;
%"Q_RES"
"1","(-1475,3400)","0","pure_quanta","I15";
;
PART_NUMBER"CS00002JB13"
PACK_TYPE"0402LF"
WATTAGE"1/16W"
TOLERANCE"5%"
VALUE"0"
MATERIAL"CHIP"
$LOCATION"R210"
CDS_LIB"pure_quanta"
CDS_LOCATION"R210"
$SEC"1"
CDS_SEC"1";
"B"
$PN"2"14;
"A"
$PN"1"28;
%"Q_RES"
"1","(-1475,4350)","0","pure_quanta","I16";
;
PART_NUMBER"CS00002JB13"
PACK_TYPE"0402LF"
TOLERANCE"5%"
MATERIAL"CHIP"
WATTAGE"1/16W"
VALUE"0"
$LOCATION"R208"
CDS_LIB"pure_quanta"
CDS_LOCATION"R208"
$SEC"1"
CDS_SEC"1";
"B"
$PN"2"20;
"A"
$PN"1"26;
%"BC847BPN"
"1","(900,575)","0","pure_quanta","I17";
;
PART_NUMBER"BA008470026"
VALUE"BC847BPN"
PART_TYPE"SMLF"
MATERIAL"IC"
LOCATION"Q142"
CDS_LMAN_SYM_OUTLINE"-50,50,50,-50"
NEEDS_NO_SIZE"TRUE"
CDS_LIB"pure_quanta"
$SEC"1"
CDS_SEC"1";
"E1"
$PN"1"9;
"C1"
$PN"6"19;
"B1"
$PN"2"17;
%"Q_RES"
"1","(2400,350)","0","pure_quanta","I18";
;
PART_NUMBER"CS03322FB03"
VALUE"33.2"
PACK_TYPE"0402LF"
MATERIAL"CHIP"
TOLERANCE"1%"
WATTAGE"1/16W"
$LOCATION"R4408"
CDS_LIB"pure_quanta"
CDS_LOCATION"R4408"
$SEC"1"
CDS_SEC"1";
"B"
$PN"2"18;
"A"
$PN"1"19;
%"Q_RES"
"1","(125,575)","0","pure_quanta","I20";
;
PART_NUMBER"CS21502FB07"
MATERIAL"CHIP"
PACK_TYPE"0402LF"
VALUE"1.5K"
$LOCATION"R4404"
WATTAGE"1/16W"
TOLERANCE"1%"
CDS_LIB"pure_quanta"
CDS_LOCATION"R4404"
$SEC"1"
CDS_SEC"1";
"B"
$PN"2"17;
"A"
$PN"1"22;
%"Q_RES"
"1","(125,1925)","0","pure_quanta","I21";
;
PART_NUMBER"CS21502FB07"
PACK_TYPE"0402LF"
VALUE"1.5K"
MATERIAL"CHIP"
$LOCATION"R4403"
WATTAGE"1/16W"
TOLERANCE"1%"
CDS_LIB"pure_quanta"
CDS_LOCATION"R4403"
$SEC"1"
CDS_SEC"1";
"B"
$PN"2"16;
"A"
$PN"1"21;
%"BC847BPN"
"1","(900,1925)","0","pure_quanta","I22";
;
PART_NUMBER"BA008470026"
VALUE"BC847BPN"
PART_TYPE"SMLF"
MATERIAL"IC"
LOCATION"Q143"
CDS_LMAN_SYM_OUTLINE"-50,50,50,-50"
NEEDS_NO_SIZE"TRUE"
CDS_LIB"pure_quanta"
$SEC"1"
CDS_SEC"1";
"E1"
$PN"1"10;
"C1"
$PN"6"15;
"B1"
$PN"2"16;
%"UNIVERSAL_GND"
"1","(1000,900)","0","logical_power","I23";
;
HDL_POWER"GND"
CDS_LIB"logical_power";
"A"9;
%"Q_RES"
"2","(1750,725)","0","pure_quanta","I24";
;
PART_NUMBER"CS24752FB03"
MATERIAL"CHIP"
PACK_TYPE"0402LF"
VALUE"4.75K"
TOLERANCE"1%"
WATTAGE"1/16W"
$LOCATION"R4406"
CDS_LIB"pure_quanta"
CDS_LOCATION"R4406"
$SEC"1"
CDS_SEC"1";
"A"
$PN"1"5;
"B"
$PN"2"19;
%"UNIVERSAL_POWER"
"1","(1750,975)","0","logical_power","I25";
;
HDL_POWER"P3V3"
CDS_LIB"logical_power";
"A"5;
%"UNIVERSAL_GND"
"1","(1000,2250)","0","logical_power","I26";
;
HDL_POWER"GND"
CDS_LIB"logical_power";
"A"10;
%"Q_RES"
"2","(1750,2075)","0","pure_quanta","I27";
;
PART_NUMBER"CS24752FB03"
PACK_TYPE"0402LF"
VALUE"4.75K"
TOLERANCE"1%"
WATTAGE"1/16W"
MATERIAL"CHIP"
$LOCATION"R4405"
CDS_LIB"pure_quanta"
CDS_LOCATION"R4405"
$SEC"1"
CDS_SEC"1";
"A"
$PN"1"6;
"B"
$PN"2"15;
%"UNIVERSAL_POWER"
"1","(1750,2325)","0","logical_power","I28";
;
HDL_POWER"P3V3"
CDS_LIB"logical_power";
"A"6;
%"Q_RES"
"2","(1175,3750)","0","pure_quanta","I29";
;
PART_NUMBER"CS11002FB07"
VALUE"100"
TOLERANCE"1%"
PACK_TYPE"0402LF"
WATTAGE"1/16W"
MATERIAL"CHIP"
$LOCATION"R220"
CDS_LIB"pure_quanta"
CDS_LOCATION"R220"
$SEC"1"
CDS_SEC"1";
"A"
$PN"1"7;
"B"
$PN"2"14;
%"UNIVERSAL_POWER"
"1","(1175,4000)","0","logical_power","I30";
;
HDL_POWER"PVNN_TERM_CPU1"
CDS_LIB"logical_power";
"A"7;
%"Q_RES"
"1","(2400,1700)","0","pure_quanta","I31";
;
PART_NUMBER"CS03322FB03"
MATERIAL"CHIP"
WATTAGE"1/16W"
VALUE"33.2"
TOLERANCE"1%"
PACK_TYPE"0402LF"
$LOCATION"R4407"
CDS_LIB"pure_quanta"
CDS_LOCATION"R4407"
$SEC"1"
CDS_SEC"1";
"B"
$PN"2"13;
"A"
$PN"1"15;
%"Q_RES"
"1","(2450,3400)","0","pure_quanta","I33";
;
PART_NUMBER"CS11002FB07"
VALUE"100"
TOLERANCE"1%"
MATERIAL"CHIP"
PACK_TYPE"0402LF"
WATTAGE"1/16W"
$LOCATION"R4294"
CDS_LIB"pure_quanta"
CDS_LOCATION"R4294"
$SEC"1"
CDS_SEC"1";
"B"
$PN"2"11;
"A"
$PN"1"14;
%"Q_RES"
"1","(2450,4350)","0","pure_quanta","I34";
;
PART_NUMBER"CS11002FB07"
WATTAGE"1/16W"
VALUE"100"
TOLERANCE"1%"
MATERIAL"CHIP"
PACK_TYPE"0402LF"
$LOCATION"R4293"
CDS_LIB"pure_quanta"
CDS_LOCATION"R4293"
$SEC"1"
CDS_SEC"1";
"B"
$PN"2"12;
"A"
$PN"1"20;
%"Q_RES"
"2","(1175,4700)","0","pure_quanta","I37";
;
PART_NUMBER"CS11002FB07"
PACK_TYPE"0402LF"
MATERIAL"CHIP"
WATTAGE"1/16W"
TOLERANCE"1%"
VALUE"100"
$LOCATION"R219"
CDS_LIB"pure_quanta"
CDS_LOCATION"R219"
$SEC"1"
CDS_SEC"1";
"A"
$PN"1"8;
"B"
$PN"2"20;
%"UNIVERSAL_POWER"
"1","(1175,4950)","0","logical_power","I38";
;
HDL_POWER"PVNN_TERM_CPU0"
CDS_LIB"logical_power";
"A"8;
%"Q_RES"
"2","(-2000,1100)","0","pure_quanta","I5";
;
PART_NUMBER"CS11002FB07"
TOLERANCE"1%"
WATTAGE"1/16W"
VALUE"100"
PACK_TYPE"0402LF"
MATERIAL"CHIP"
$LOCATION"R4402"
CDS_LIB"pure_quanta"
CDS_LOCATION"R4402"
$SEC"1"
CDS_SEC"1";
"A"
$PN"1"1;
"B"
$PN"2"27;
%"Q_RES"
"1","(-1650,825)","0","pure_quanta","I6";
;
PART_NUMBER"CS21502FB07"
TOLERANCE"1%"
MATERIAL"CHIP"
WATTAGE"1/16W"
PACK_TYPE"0402LF"
VALUE"1.5K"
LOCATION"R204"
CDS_LIB"pure_quanta"
$SEC"1"
CDS_SEC"1";
"B"
$PN"2"24;
"A"
$PN"1"27;
%"UNIVERSAL_POWER"
"1","(-2000,1300)","0","logical_power","I7";
;
HDL_POWER"PVNN_TERM_CPU1"
CDS_LIB"logical_power";
"A"1;
%"Q_RES"
"2","(-2000,2450)","0","pure_quanta","I8";
;
PART_NUMBER"CS11002FB07"
WATTAGE"1/16W"
VALUE"100"
PACK_TYPE"0402LF"
MATERIAL"CHIP"
TOLERANCE"1%"
$LOCATION"R4401"
CDS_LIB"pure_quanta"
CDS_LOCATION"R4401"
$SEC"1"
CDS_SEC"1";
"A"
$PN"1"4;
"B"
$PN"2"25;
%"Q_RES"
"1","(-1650,2175)","0","pure_quanta","I9";
;
PART_NUMBER"CS21502FB07"
PACK_TYPE"0402LF"
TOLERANCE"1%"
MATERIAL"CHIP"
WATTAGE"1/16W"
VALUE"1.5K"
LOCATION"R203"
CDS_LIB"pure_quanta"
$SEC"1"
CDS_SEC"1";
"B"
$PN"2"23;
"A"
$PN"1"25;
END.
